(kicad_pcb
	(version 20260206)
	(generator "pcbnew")
	(generator_version "10.0")
	(general
		(thickness 1.6)
		(legacy_teardrops no)
	)
	(paper "A4")
	(title_block
		(title "Wiwynn_Tioga_Pass_MB.brd")
		(comment 1 "Tioga Pass / footprints 249-256 of 4770")
	)
	(layers
		(0 "F.Cu" signal "TOP")
		(4 "In1.Cu" signal "L2GND")
		(6 "In2.Cu" signal "L3")
		(8 "In3.Cu" signal "L4GND")
		(10 "In4.Cu" signal "L5")
		(12 "In5.Cu" signal "L6GND")
		(14 "In6.Cu" signal "L7VCC")
		(16 "In7.Cu" signal "L8VCC")
		(18 "In8.Cu" signal "L9GND")
		(20 "In9.Cu" signal "L10")
		(22 "In10.Cu" signal "L11GND")
		(24 "In11.Cu" signal "L12")
		(26 "In12.Cu" signal "L13GND")
		(2 "B.Cu" signal "BOTTOM")
		(9 "F.Adhes" user "F.Adhesive")
		(11 "B.Adhes" user "B.Adhesive")
		(13 "F.Paste" user "Package Geometry/Pastemask Top")
		(15 "B.Paste" user "Package Geometry/Pastemask Bottom")
		(5 "F.SilkS" user "Ref Des/Silkscreen Top")
		(7 "B.SilkS" user "Ref Des/Silkscreen Bottom")
		(1 "F.Mask" user "Board Geometry/Soldermask Top")
		(3 "B.Mask" user "Board Geometry/Soldermask Bottom")
		(17 "Dwgs.User" user "User.Drawings")
		(19 "Cmts.User" user "User.Comments")
		(21 "Eco1.User" user "User.Eco1")
		(23 "Eco2.User" user "User.Eco2")
		(25 "Edge.Cuts" user "Board Geometry/Outline")
		(27 "Margin" user)
		(31 "F.CrtYd" user "Package Geometry/Place Bound Top")
		(29 "B.CrtYd" user "Package Geometry/Place Bound Bottom")
		(35 "F.Fab" user "Ref Des/Assembly Top")
		(33 "B.Fab" user "Ref Des/Assembly Bottom")
	)
	(footprint ""
		(layer "F.Cu")
		(at 352.9965 -151.257 -90)
		(property "Reference" "C7A12"
			(at 0 0 270)
			(layer "F.SilkS")
			(hide yes)
			(effects
				(font
					(size 1.27 1.27)
				)
			)
		)
		(property "Value" ""
			(at 0 0 270)
			(layer "F.Fab")
			(effects
				(font
					(size 1.27 1.27)
				)
			)
		)
		(duplicate_pad_numbers_are_jumpers no)
		(fp_poly
			(pts
				(xy 0.3048 -0.1016) (xy 0.3048 0.9906) (xy -0.3048 0.9906) (xy -0.3048 -0.1016)
			)
			(stroke
				(width 0)
				(type default)
			)
			(fill no)
			(layer "F.CrtYd")
		)
		(fp_line
			(start -0.3048 0.9906)
			(end 0.3048 0.9906)
			(stroke
				(width 0.1)
				(type default)
			)
			(layer "F.Fab")
		)
		(fp_line
			(start 0.3048 0.9906)
			(end 0.3048 -0.1016)
			(stroke
				(width 0.1)
				(type default)
			)
			(layer "F.Fab")
		)
		(fp_line
			(start -0.3048 -0.1016)
			(end -0.3048 0.9906)
			(stroke
				(width 0.1)
				(type default)
			)
			(layer "F.Fab")
		)
		(fp_line
			(start 0.3048 -0.1016)
			(end -0.3048 -0.1016)
			(stroke
				(width 0.1)
				(type default)
			)
			(layer "F.Fab")
		)
		(pad "1" smd rect
			(at 0 0 270)
			(size 0.508 0.508)
			(layers "F.Cu" "F.Mask" "F.Paste")
			(net "VR_PVDDQ_DEF_PH1_BOOT")
		)
		(pad "2" smd rect
			(at 0 0.889 270)
			(size 0.508 0.508)
			(layers "F.Cu" "F.Mask" "F.Paste")
			(net "VR_PVDDQ_DEF_PH1_PHASE")
		)
		(zone
			(layer "F.Cu")
			(hatch none 0.5)
			(connect_pads
				(clearance 0)
			)
			(min_thickness 0.25)
			(keepout
				(tracks not_allowed)
				(vias allowed)
				(pads allowed)
				(copperpour not_allowed)
				(footprints allowed)
			)
			(placement
				(enabled no)
				(sheetname "")
			)
			(fill
				(thermal_gap 0.5)
				(thermal_bridge_width 0.5)
				(island_removal_mode 0)
			)
			(polygon
				(pts
					(xy 352.3615 -151.511) (xy 352.3615 -151.003) (xy 352.7425 -151.003) (xy 352.7425 -151.511)
				)
			)
		)
		(zone
			(layer "F.Cu")
			(hatch none 0.5)
			(connect_pads
				(clearance 0)
			)
			(min_thickness 0.25)
			(keepout
				(tracks allowed)
				(vias not_allowed)
				(pads allowed)
				(copperpour not_allowed)
				(footprints allowed)
			)
			(placement
				(enabled no)
				(sheetname "")
			)
			(fill
				(thermal_gap 0.5)
				(thermal_bridge_width 0.5)
				(island_removal_mode 0)
			)
			(polygon
				(pts
					(xy 352.7425 -151.511) (xy 352.7425 -151.003) (xy 352.3615 -151.003) (xy 352.3615 -151.511)
				)
			)
		)
	)
	(footprint ""
		(layer "F.Cu")
		(at 253.392432 -140.208 90)
		(property "Reference" "C5A14"
			(at 1.848866 0.752348 90)
			(unlocked yes)
			(layer "F.SilkS")
			(effects
				(font
					(size 1.27 0.9652)
					(thickness 0.1524)
				)
			)
		)
		(property "Value" ""
			(at 0 0 90)
			(layer "F.Fab")
			(effects
				(font
					(size 1.27 1.27)
				)
			)
		)
		(duplicate_pad_numbers_are_jumpers no)
		(fp_rect
			(start -0.500126 1.598422)
			(end 0.500126 -0.201422)
			(stroke
				(width 0)
				(type default)
			)
			(fill no)
			(layer "F.CrtYd")
		)
		(fp_line
			(start 0.500126 -0.201422)
			(end 0.500126 1.598422)
			(stroke
				(width 0.1)
				(type default)
			)
			(layer "F.Fab")
		)
		(fp_line
			(start -0.500126 -0.201422)
			(end 0.500126 -0.201422)
			(stroke
				(width 0.1)
				(type default)
			)
			(layer "F.Fab")
		)
		(fp_line
			(start 0.500126 1.598422)
			(end -0.500126 1.598422)
			(stroke
				(width 0.1)
				(type default)
			)
			(layer "F.Fab")
		)
		(fp_line
			(start -0.500126 1.598422)
			(end -0.500126 -0.201422)
			(stroke
				(width 0.1)
				(type default)
			)
			(layer "F.Fab")
		)
		(pad "1" smd rect
			(at 0 0)
			(size 0.889 0.9906)
			(layers "F.Cu" "F.Mask" "F.Paste")
			(net "PVDDQ_DEF")
		)
		(pad "2" smd rect
			(at 0 1.397)
			(size 0.889 0.9906)
			(layers "F.Cu" "F.Mask" "F.Paste")
			(net "GND")
		)
		(zone
			(layer "F.Cu")
			(hatch none 0.5)
			(connect_pads
				(clearance 0)
			)
			(min_thickness 0.25)
			(keepout
				(tracks allowed)
				(vias not_allowed)
				(pads allowed)
				(copperpour not_allowed)
				(footprints allowed)
			)
			(placement
				(enabled no)
				(sheetname "")
			)
			(fill
				(thermal_gap 0.5)
				(thermal_bridge_width 0.5)
				(island_removal_mode 0)
			)
			(polygon
				(pts
					(xy 254.344932 -139.7127) (xy 254.344932 -140.7033) (xy 253.836932 -140.7033) (xy 253.836932 -139.7127)
				)
			)
		)
		(zone
			(layer "F.Cu")
			(hatch none 0.5)
			(connect_pads
				(clearance 0)
			)
			(min_thickness 0.25)
			(keepout
				(tracks not_allowed)
				(vias allowed)
				(pads allowed)
				(copperpour not_allowed)
				(footprints allowed)
			)
			(placement
				(enabled no)
				(sheetname "")
			)
			(fill
				(thermal_gap 0.5)
				(thermal_bridge_width 0.5)
				(island_removal_mode 0)
			)
			(polygon
				(pts
					(xy 254.344932 -139.7127) (xy 254.344932 -140.7033) (xy 253.836932 -140.7033) (xy 253.836932 -139.7127)
				)
			)
		)
	)
	(footprint ""
		(layer "F.Cu")
		(at 427.56836 -45.872654)
		(property "Reference" "R25W78"
			(at -0.8382 -0.67818 0)
			(unlocked yes)
			(layer "F.SilkS")
			(effects
				(font
					(size 0.4064 0.254)
					(thickness 0.1524)
				)
				(justify left)
			)
		)
		(property "Value" ""
			(at 0 0 0)
			(layer "F.Fab")
			(effects
				(font
					(size 1.27 1.27)
				)
			)
		)
		(duplicate_pad_numbers_are_jumpers no)
		(fp_poly
			(pts
				(xy -0.2794 -0.1016) (xy 0.2794 -0.1016) (xy 0.2794 0.9906) (xy -0.2794 0.9906)
			)
			(stroke
				(width 0)
				(type default)
			)
			(fill no)
			(layer "F.CrtYd")
		)
		(fp_line
			(start -0.2794 -0.1016)
			(end -0.2794 0.9906)
			(stroke
				(width 0.1)
				(type default)
			)
			(layer "F.Fab")
		)
		(fp_line
			(start -0.2794 0.9906)
			(end 0.2794 0.9906)
			(stroke
				(width 0.1)
				(type default)
			)
			(layer "F.Fab")
		)
		(fp_line
			(start 0.2794 -0.1016)
			(end -0.2794 -0.1016)
			(stroke
				(width 0.1)
				(type default)
			)
			(layer "F.Fab")
		)
		(fp_line
			(start 0.2794 0.9906)
			(end 0.2794 -0.1016)
			(stroke
				(width 0.1)
				(type default)
			)
			(layer "F.Fab")
		)
		(pad "1" smd rect
			(at 0 0)
			(size 0.508 0.508)
			(layers "F.Cu" "F.Mask" "F.Paste")
			(net "SPI_BMC_BT_CS_R_N")
		)
		(pad "2" smd rect
			(at 0 0.889)
			(size 0.508 0.508)
			(layers "F.Cu" "F.Mask" "F.Paste")
			(net "SPI_BMC_BT_CS_N")
		)
		(zone
			(layer "F.Cu")
			(hatch none 0.5)
			(connect_pads
				(clearance 0)
			)
			(min_thickness 0.25)
			(keepout
				(tracks allowed)
				(vias not_allowed)
				(pads allowed)
				(copperpour not_allowed)
				(footprints allowed)
			)
			(placement
				(enabled no)
				(sheetname "")
			)
			(fill
				(thermal_gap 0.5)
				(thermal_bridge_width 0.5)
				(island_removal_mode 0)
			)
			(polygon
				(pts
					(xy 427.31436 -45.618654) (xy 427.82236 -45.618654) (xy 427.82236 -45.237654) (xy 427.31436 -45.237654)
				)
			)
		)
		(zone
			(layer "F.Cu")
			(hatch none 0.5)
			(connect_pads
				(clearance 0)
			)
			(min_thickness 0.25)
			(keepout
				(tracks not_allowed)
				(vias allowed)
				(pads allowed)
				(copperpour not_allowed)
				(footprints allowed)
			)
			(placement
				(enabled no)
				(sheetname "")
			)
			(fill
				(thermal_gap 0.5)
				(thermal_bridge_width 0.5)
				(island_removal_mode 0)
			)
			(polygon
				(pts
					(xy 427.31436 -45.237654) (xy 427.82236 -45.237654) (xy 427.82236 -45.618654) (xy 427.31436 -45.618654)
				)
			)
		)
	)
	(footprint ""
		(layer "F.Cu")
		(at 468.112856 -25.762204 180)
		(property "Reference" "R8E35"
			(at 0 0 180)
			(layer "F.SilkS")
			(hide yes)
			(effects
				(font
					(size 1.27 1.27)
				)
			)
		)
		(property "Value" ""
			(at 0 0 180)
			(layer "F.Fab")
			(effects
				(font
					(size 1.27 1.27)
				)
			)
		)
		(duplicate_pad_numbers_are_jumpers no)
		(fp_rect
			(start 0.2794 -0.1016)
			(end -0.2794 0.9906)
			(stroke
				(width 0)
				(type default)
			)
			(fill no)
			(layer "F.CrtYd")
		)
		(fp_line
			(start 0.2794 0.9906)
			(end 0.2794 -0.1016)
			(stroke
				(width 0.1)
				(type default)
			)
			(layer "F.Fab")
		)
		(fp_line
			(start 0.2794 -0.1016)
			(end -0.2794 -0.1016)
			(stroke
				(width 0.1)
				(type default)
			)
			(layer "F.Fab")
		)
		(fp_line
			(start -0.2794 0.9906)
			(end 0.2794 0.9906)
			(stroke
				(width 0.1)
				(type default)
			)
			(layer "F.Fab")
		)
		(fp_line
			(start -0.2794 -0.1016)
			(end -0.2794 0.9906)
			(stroke
				(width 0.1)
				(type default)
			)
			(layer "F.Fab")
		)
		(pad "1" smd rect
			(at 0 0 180)
			(size 0.508 0.508)
			(layers "F.Cu" "F.Mask" "F.Paste")
			(net "VR_P3V3_STBY_BOOT")
		)
		(pad "2" smd rect
			(at 0 0.889 180)
			(size 0.508 0.508)
			(layers "F.Cu" "F.Mask" "F.Paste")
			(net "VR_P3V3_STBY_BOOT_R")
		)
		(zone
			(layer "F.Cu")
			(hatch none 0.5)
			(connect_pads
				(clearance 0)
			)
			(min_thickness 0.25)
			(keepout
				(tracks not_allowed)
				(vias allowed)
				(pads allowed)
				(copperpour not_allowed)
				(footprints allowed)
			)
			(placement
				(enabled no)
				(sheetname "")
			)
			(fill
				(thermal_gap 0.5)
				(thermal_bridge_width 0.5)
				(island_removal_mode 0)
			)
			(polygon
				(pts
					(xy 467.858856 -26.016204) (xy 468.366856 -26.016204) (xy 468.366856 -26.397204) (xy 467.858856 -26.397204)
				)
			)
		)
		(zone
			(layer "F.Cu")
			(hatch none 0.5)
			(connect_pads
				(clearance 0)
			)
			(min_thickness 0.25)
			(keepout
				(tracks allowed)
				(vias not_allowed)
				(pads allowed)
				(copperpour not_allowed)
				(footprints allowed)
			)
			(placement
				(enabled no)
				(sheetname "")
			)
			(fill
				(thermal_gap 0.5)
				(thermal_bridge_width 0.5)
				(island_removal_mode 0)
			)
			(polygon
				(pts
					(xy 467.858856 -26.016204) (xy 468.366856 -26.016204) (xy 468.366856 -26.397204) (xy 467.858856 -26.397204)
				)
			)
		)
	)
	(footprint ""
		(layer "F.Cu")
		(at 35.9664 -77.7494 -90)
		(property "Reference" "RT13"
			(at 0 0 270)
			(layer "F.SilkS")
			(hide yes)
			(effects
				(font
					(size 1.27 1.27)
				)
			)
		)
		(property "Value" "*"
			(at -0.0254 -2.6289 270)
			(unlocked yes)
			(layer "F.Fab")
			(hide yes)
			(effects
				(font
					(size 1.27 1.016)
					(thickness 0.1524)
				)
			)
		)
		(property "Device Type" "1R3F-GP_RCL_GP-1R3F-GP,64.1R00A"
			(at -0.0254 -4.1529 270)
			(unlocked yes)
			(layer "F.Fab")
			(hide yes)
			(effects
				(font
					(size 1.27 1.016)
					(thickness 0.1524)
				)
			)
		)
		(duplicate_pad_numbers_are_jumpers no)
		(fp_line
			(start -0.4826 0)
			(end -0.2032 0)
			(stroke
				(width 0.2032)
				(type default)
			)
			(layer "F.SilkS")
		)
		(fp_line
			(start 0.2032 0)
			(end 0.4826 0)
			(stroke
				(width 0.2032)
				(type default)
			)
			(layer "F.SilkS")
		)
		(fp_rect
			(start -0.5842 1.3335)
			(end 0.5842 -1.3335)
			(stroke
				(width 0)
				(type default)
			)
			(fill no)
			(layer "F.CrtYd")
		)
		(fp_rect
			(start -0.5842 1.3335)
			(end 0.5842 -1.3335)
			(stroke
				(width 0)
				(type default)
			)
			(fill no)
			(layer "F.Fab")
		)
		(pad "1" smd custom
			(at 0 -0.762 270)
			(size 0.2159 0.2159)
			(layers "F.Cu" "F.Mask" "F.Paste")
			(net "VR_PVCCIN_CPU1_PHASE4_RC")
			(options
				(clearance outline)
				(anchor circle)
			)
			(primitives
				(gr_poly
					(pts
						(arc
							(start -0.3302 -0.4318)
							(mid -0.402042 -0.402042)
							(end -0.4318 -0.3302)
						)
						(arc
							(start -0.4318 0.3302)
							(mid -0.402042 0.402042)
							(end -0.3302 0.4318)
						)
						(arc
							(start 0.3302 0.4318)
							(mid 0.402042 0.402042)
							(end 0.4318 0.3302)
						)
						(arc
							(start 0.4318 -0.3302)
							(mid 0.402042 -0.402042)
							(end 0.3302 -0.4318)
						)
					)
					(width 0)
					(fill yes)
				)
			)
		)
		(pad "2" smd custom
			(at 0 0.762 270)
			(size 0.2159 0.2159)
			(layers "F.Cu" "F.Mask" "F.Paste")
			(net "GND")
			(options
				(clearance outline)
				(anchor circle)
			)
			(primitives
				(gr_poly
					(pts
						(arc
							(start -0.3302 -0.4318)
							(mid -0.402042 -0.402042)
							(end -0.4318 -0.3302)
						)
						(arc
							(start -0.4318 0.3302)
							(mid -0.402042 0.402042)
							(end -0.3302 0.4318)
						)
						(arc
							(start 0.3302 0.4318)
							(mid 0.402042 0.402042)
							(end 0.4318 0.3302)
						)
						(arc
							(start 0.4318 -0.3302)
							(mid 0.402042 -0.402042)
							(end 0.3302 -0.4318)
						)
					)
					(width 0)
					(fill yes)
				)
			)
		)
	)
	(footprint ""
		(layer "F.Cu")
		(at 104.5591 -3.3528 90)
		(property "Reference" "C2G14"
			(at 1.848866 0.752348 90)
			(unlocked yes)
			(layer "F.SilkS")
			(effects
				(font
					(size 1.27 0.9652)
					(thickness 0.1524)
				)
			)
		)
		(property "Value" ""
			(at 0 0 90)
			(layer "F.Fab")
			(effects
				(font
					(size 1.27 1.27)
				)
			)
		)
		(duplicate_pad_numbers_are_jumpers no)
		(fp_rect
			(start -0.500126 1.598422)
			(end 0.500126 -0.201422)
			(stroke
				(width 0)
				(type default)
			)
			(fill no)
			(layer "F.CrtYd")
		)
		(fp_line
			(start 0.500126 -0.201422)
			(end 0.500126 1.598422)
			(stroke
				(width 0.1)
				(type default)
			)
			(layer "F.Fab")
		)
		(fp_line
			(start -0.500126 -0.201422)
			(end 0.500126 -0.201422)
			(stroke
				(width 0.1)
				(type default)
			)
			(layer "F.Fab")
		)
		(fp_line
			(start 0.500126 1.598422)
			(end -0.500126 1.598422)
			(stroke
				(width 0.1)
				(type default)
			)
			(layer "F.Fab")
		)
		(fp_line
			(start -0.500126 1.598422)
			(end -0.500126 -0.201422)
			(stroke
				(width 0.1)
				(type default)
			)
			(layer "F.Fab")
		)
		(pad "1" smd rect
			(at 0 0)
			(size 0.889 0.9906)
			(layers "F.Cu" "F.Mask" "F.Paste")
			(net "PVDDQ_GHJ")
		)
		(pad "2" smd rect
			(at 0 1.397)
			(size 0.889 0.9906)
			(layers "F.Cu" "F.Mask" "F.Paste")
			(net "GND")
		)
		(zone
			(layer "F.Cu")
			(hatch none 0.5)
			(connect_pads
				(clearance 0)
			)
			(min_thickness 0.25)
			(keepout
				(tracks allowed)
				(vias not_allowed)
				(pads allowed)
				(copperpour not_allowed)
				(footprints allowed)
			)
			(placement
				(enabled no)
				(sheetname "")
			)
			(fill
				(thermal_gap 0.5)
				(thermal_bridge_width 0.5)
				(island_removal_mode 0)
			)
			(polygon
				(pts
					(xy 105.5116 -2.8575) (xy 105.5116 -3.8481) (xy 105.0036 -3.8481) (xy 105.0036 -2.8575)
				)
			)
		)
		(zone
			(layer "F.Cu")
			(hatch none 0.5)
			(connect_pads
				(clearance 0)
			)
			(min_thickness 0.25)
			(keepout
				(tracks not_allowed)
				(vias allowed)
				(pads allowed)
				(copperpour not_allowed)
				(footprints allowed)
			)
			(placement
				(enabled no)
				(sheetname "")
			)
			(fill
				(thermal_gap 0.5)
				(thermal_bridge_width 0.5)
				(island_removal_mode 0)
			)
			(polygon
				(pts
					(xy 105.5116 -2.8575) (xy 105.5116 -3.8481) (xy 105.0036 -3.8481) (xy 105.0036 -2.8575)
				)
			)
		)
	)
	(footprint ""
		(layer "F.Cu")
		(at 363.7788 -133.9977)
		(property "Reference" "R7B1"
			(at 0 0 0)
			(layer "F.SilkS")
			(hide yes)
			(effects
				(font
					(size 1.27 1.27)
				)
			)
		)
		(property "Value" ""
			(at 0 0 0)
			(layer "F.Fab")
			(effects
				(font
					(size 1.27 1.27)
				)
			)
		)
		(duplicate_pad_numbers_are_jumpers no)
		(fp_poly
			(pts
				(xy -0.2794 -0.1016) (xy 0.2794 -0.1016) (xy 0.2794 0.9906) (xy -0.2794 0.9906)
			)
			(stroke
				(width 0)
				(type default)
			)
			(fill no)
			(layer "F.CrtYd")
		)
		(fp_line
			(start -0.2794 -0.1016)
			(end -0.2794 0.9906)
			(stroke
				(width 0.1)
				(type default)
			)
			(layer "F.Fab")
		)
		(fp_line
			(start -0.2794 0.9906)
			(end 0.2794 0.9906)
			(stroke
				(width 0.1)
				(type default)
			)
			(layer "F.Fab")
		)
		(fp_line
			(start 0.2794 -0.1016)
			(end -0.2794 -0.1016)
			(stroke
				(width 0.1)
				(type default)
			)
			(layer "F.Fab")
		)
		(fp_line
			(start 0.2794 0.9906)
			(end 0.2794 -0.1016)
			(stroke
				(width 0.1)
				(type default)
			)
			(layer "F.Fab")
		)
		(pad "1" smd rect
			(at 0 0)
			(size 0.508 0.508)
			(layers "F.Cu" "F.Mask" "F.Paste")
			(net "IRQ_PVDDQ_DEF_VRHOT_LVT3_R_N")
		)
		(pad "2" smd rect
			(at 0 0.889)
			(size 0.508 0.508)
			(layers "F.Cu" "F.Mask" "F.Paste")
			(net "IRQ_PVDDQ_DEF_VRHOT_LVT3_N")
		)
		(zone
			(layer "F.Cu")
			(hatch none 0.5)
			(connect_pads
				(clearance 0)
			)
			(min_thickness 0.25)
			(keepout
				(tracks allowed)
				(vias not_allowed)
				(pads allowed)
				(copperpour not_allowed)
				(footprints allowed)
			)
			(placement
				(enabled no)
				(sheetname "")
			)
			(fill
				(thermal_gap 0.5)
				(thermal_bridge_width 0.5)
				(island_removal_mode 0)
			)
			(polygon
				(pts
					(xy 363.5248 -133.7437) (xy 364.0328 -133.7437) (xy 364.0328 -133.3627) (xy 363.5248 -133.3627)
				)
			)
		)
		(zone
			(layer "F.Cu")
			(hatch none 0.5)
			(connect_pads
				(clearance 0)
			)
			(min_thickness 0.25)
			(keepout
				(tracks not_allowed)
				(vias allowed)
				(pads allowed)
				(copperpour not_allowed)
				(footprints allowed)
			)
			(placement
				(enabled no)
				(sheetname "")
			)
			(fill
				(thermal_gap 0.5)
				(thermal_bridge_width 0.5)
				(island_removal_mode 0)
			)
			(polygon
				(pts
					(xy 363.5248 -133.3627) (xy 364.0328 -133.3627) (xy 364.0328 -133.7437) (xy 363.5248 -133.7437)
				)
			)
		)
	)
	(footprint ""
		(layer "F.Cu")
		(at 478.0026 -22.4028)
		(property "Reference" "C8E11"
			(at 0 0 0)
			(layer "F.SilkS")
			(hide yes)
			(effects
				(font
					(size 1.27 1.27)
				)
			)
		)
		(property "Value" "*"
			(at -0.0762 -6.2357 0)
			(unlocked yes)
			(layer "F.Fab")
			(hide yes)
			(effects
				(font
					(size 1.27 1.016)
					(thickness 0.1524)
				)
			)
		)
		(property "Device Type" "SC22U16V5MX-4-GP_SMD-BCG5-SC22A"
			(at -0.0762 -8.2677 0)
			(unlocked yes)
			(layer "F.Fab")
			(hide yes)
			(effects
				(font
					(size 1.27 1.016)
					(thickness 0.1524)
				)
			)
		)
		(duplicate_pad_numbers_are_jumpers no)
		(fp_line
			(start 0.635 0)
			(end -0.635 0)
			(stroke
				(width 0.508)
				(type default)
			)
			(layer "F.SilkS")
		)
		(fp_rect
			(start -0.9652 1.778)
			(end 0.9652 -1.778)
			(stroke
				(width 0)
				(type default)
			)
			(fill no)
			(layer "F.CrtYd")
		)
		(fp_poly
			(pts
				(xy -0.9652 -1.778) (xy 0.9652 -1.778) (xy 0.9652 1.778) (xy -0.9652 1.778)
			)
			(stroke
				(width 0)
				(type default)
			)
			(fill no)
			(layer "F.Fab")
		)
		(pad "1" smd rect
			(at 0 -0.9652)
			(size 1.397 1.143)
			(layers "F.Cu" "F.Mask" "F.Paste")
			(net "VR_FET_SW_P12V_STBY_P3V3_STBY")
		)
		(pad "2" smd rect
			(at 0 0.9652)
			(size 1.397 1.143)
			(layers "F.Cu" "F.Mask" "F.Paste")
			(net "GND")
		)
	)
)
